# T6G (Grand Teton) — schematic netlist excerpt (pin names and nets, part order shuffled) for the footprints in the layout excerpt that follows; sources: Cadence DE-HDL packaged netlist, KiCad conversion of 04192023_DAF0TMB3IC0_F0TG_MB_C_brd_V02_OCP.brd

R434  Q_RES  33 5% CHIP  pkg 0402LF  page 28 : A = CPU0_PWR_GD_OUT ; B = CPU1_PWR_GD_IN
R4544  Q_RES  100K 1% EMPTY  pkg 0402LF  page 124 : A = HGX_DETECT_N ; B = GND

(kicad_pcb
	(version 20260206)
	(generator "pcbnew")
	(generator_version "10.0")
	(general
		(thickness 1.6)
		(legacy_teardrops no)
	)
	(paper "A4")
	(title_block
		(title "04192023_DAF0TMB3IC0_F0TG_MB_C_brd_V02_OCP.brd")
		(comment 1 "Grand Teton / footprints 5970-5971 of 8354")
	)
	(layers
		(0 "F.Cu" signal "TOP")
		(4 "In1.Cu" signal "GND")
		(6 "In2.Cu" signal "IN1")
		(8 "In3.Cu" signal "GND1")
		(10 "In4.Cu" signal "IN2")
		(12 "In5.Cu" signal "GND2")
		(14 "In6.Cu" signal "IN3")
		(16 "In7.Cu" signal "GND3")
		(18 "In8.Cu" signal "VCC")
		(20 "In9.Cu" signal "VCC1")
		(22 "In10.Cu" signal "GND4")
		(24 "In11.Cu" signal "IN4")
		(26 "In12.Cu" signal "GND5")
		(28 "In13.Cu" signal "IN5")
		(30 "In14.Cu" signal "GND6")
		(32 "In15.Cu" signal "IN6")
		(34 "In16.Cu" signal "GND7")
		(2 "B.Cu" signal "BOTTOM")
		(9 "F.Adhes" user "F.Adhesive")
		(11 "B.Adhes" user "B.Adhesive")
		(13 "F.Paste" user "Package Geometry/Pastemask Top")
		(15 "B.Paste" user "Package Geometry/Pastemask Bottom")
		(5 "F.SilkS" user "Ref Des/Silkscreen Top")
		(7 "B.SilkS" user "Ref Des/Silkscreen Bottom")
		(1 "F.Mask" user "Board Geometry/Soldermask Top")
		(3 "B.Mask" user "Board Geometry/Soldermask Bottom")
		(17 "Dwgs.User" user "User.Drawings")
		(19 "Cmts.User" user "User.Comments")
		(21 "Eco1.User" user "User.Eco1")
		(23 "Eco2.User" user "User.Eco2")
		(25 "Edge.Cuts" user "Board Geometry/Outline")
		(27 "Margin" user)
		(31 "F.CrtYd" user "Package Geometry/Place Bound Top")
		(29 "B.CrtYd" user "Package Geometry/Place Bound Bottom")
		(35 "F.Fab" user "Ref Des/Assembly Top")
		(33 "B.Fab" user "Ref Des/Assembly Bottom")
	)
	(footprint ""
		(layer "B.Cu")
		(at 406.698958 -325.878952 180)
		(property "Reference" "R434"
			(at 0 0 0)
			(layer "B.SilkS")
			(hide yes)
			(effects
				(font
					(size 1.27 1.27)
				)
				(justify mirror)
			)
		)
		(property "Value" ""
			(at 0 0 0)
			(layer "B.Fab")
			(effects
				(font
					(size 1.27 1.27)
				)
				(justify mirror)
			)
		)
		(duplicate_pad_numbers_are_jumpers no)
		(fp_line
			(start 0.7874 0.4064)
			(end 0.7874 -0.4064)
			(stroke
				(width 0.1524)
				(type default)
			)
			(layer "B.SilkS")
		)
		(fp_line
			(start 0.7874 -0.4064)
			(end -0.7874 -0.4064)
			(stroke
				(width 0.1524)
				(type default)
			)
			(layer "B.SilkS")
		)
		(fp_line
			(start -0.7874 0.4064)
			(end 0.7874 0.4064)
			(stroke
				(width 0.1524)
				(type default)
			)
			(layer "B.SilkS")
		)
		(fp_line
			(start -0.7874 -0.4064)
			(end -0.7874 0.4064)
			(stroke
				(width 0.1524)
				(type default)
			)
			(layer "B.SilkS")
		)
		(fp_line
			(start 0.67945 0.3048)
			(end 0.67945 -0.305054)
			(stroke
				(width 0.1)
				(type default)
			)
			(layer "B.Fab")
		)
		(fp_line
			(start 0.67945 -0.305054)
			(end 0.12065 -0.305054)
			(stroke
				(width 0.1)
				(type default)
			)
			(layer "B.Fab")
		)
		(fp_line
			(start 0.12065 0.3048)
			(end 0.67945 0.3048)
			(stroke
				(width 0.1)
				(type default)
			)
			(layer "B.Fab")
		)
		(fp_line
			(start 0.12065 0.2794)
			(end 0.12065 0.3048)
			(stroke
				(width 0.1)
				(type default)
			)
			(layer "B.Fab")
		)
		(fp_line
			(start 0.12065 -0.2794)
			(end -0.12065 -0.2794)
			(stroke
				(width 0.1)
				(type default)
			)
			(layer "B.Fab")
		)
		(fp_line
			(start 0.12065 -0.305054)
			(end 0.12065 -0.2794)
			(stroke
				(width 0.1)
				(type default)
			)
			(layer "B.Fab")
		)
		(fp_line
			(start -0.120396 0.3048)
			(end -0.120396 0.2794)
			(stroke
				(width 0.1)
				(type default)
			)
			(layer "B.Fab")
		)
		(fp_line
			(start -0.120396 0.2794)
			(end 0.12065 0.2794)
			(stroke
				(width 0.1)
				(type default)
			)
			(layer "B.Fab")
		)
		(fp_line
			(start -0.12065 -0.2794)
			(end -0.12065 -0.3048)
			(stroke
				(width 0.1)
				(type default)
			)
			(layer "B.Fab")
		)
		(fp_line
			(start -0.12065 -0.3048)
			(end -0.67945 -0.3048)
			(stroke
				(width 0.1)
				(type default)
			)
			(layer "B.Fab")
		)
		(fp_line
			(start -0.67945 0.3048)
			(end -0.120396 0.3048)
			(stroke
				(width 0.1)
				(type default)
			)
			(layer "B.Fab")
		)
		(fp_line
			(start -0.67945 -0.3048)
			(end -0.67945 0.3048)
			(stroke
				(width 0.1)
				(type default)
			)
			(layer "B.Fab")
		)
		(pad "1" smd circle
			(at 0.40005 0)
			(size 0 0)
			(layers "B.Cu" "B.Mask" "B.Paste")
			(net "CPU0_PWR_GD_OUT")
		)
		(pad "2" smd circle
			(at -0.40005 0)
			(size 0 0)
			(layers "B.Cu" "B.Mask" "B.Paste")
			(net "CPU1_PWR_GD_IN")
		)
	)
	(footprint ""
		(layer "B.Cu")
		(at 103.632 -415.925 -90)
		(property "Reference" "R4544"
			(at 0 0 90)
			(layer "B.SilkS")
			(hide yes)
			(effects
				(font
					(size 1.27 1.27)
				)
				(justify mirror)
			)
		)
		(property "Value" ""
			(at 0 0 90)
			(layer "B.Fab")
			(effects
				(font
					(size 1.27 1.27)
				)
				(justify mirror)
			)
		)
		(duplicate_pad_numbers_are_jumpers no)
		(fp_line
			(start -0.7874 0.4064)
			(end 0.7874 0.4064)
			(stroke
				(width 0.1524)
				(type default)
			)
			(layer "B.SilkS")
		)
		(fp_line
			(start 0.7874 0.4064)
			(end 0.7874 -0.4064)
			(stroke
				(width 0.1524)
				(type default)
			)
			(layer "B.SilkS")
		)
		(fp_line
			(start -0.7874 -0.4064)
			(end -0.7874 0.4064)
			(stroke
				(width 0.1524)
				(type default)
			)
			(layer "B.SilkS")
		)
		(fp_line
			(start 0.7874 -0.4064)
			(end -0.7874 -0.4064)
			(stroke
				(width 0.1524)
				(type default)
			)
			(layer "B.SilkS")
		)
		(fp_line
			(start -0.67945 0.3048)
			(end -0.120396 0.3048)
			(stroke
				(width 0.1)
				(type default)
			)
			(layer "B.Fab")
		)
		(fp_line
			(start -0.120396 0.3048)
			(end -0.120396 0.2794)
			(stroke
				(width 0.1)
				(type default)
			)
			(layer "B.Fab")
		)
		(fp_line
			(start 0.12065 0.3048)
			(end 0.67945 0.3048)
			(stroke
				(width 0.1)
				(type default)
			)
			(layer "B.Fab")
		)
		(fp_line
			(start 0.67945 0.3048)
			(end 0.67945 -0.305054)
			(stroke
				(width 0.1)
				(type default)
			)
			(layer "B.Fab")
		)
		(fp_line
			(start -0.120396 0.2794)
			(end 0.12065 0.2794)
			(stroke
				(width 0.1)
				(type default)
			)
			(layer "B.Fab")
		)
		(fp_line
			(start 0.12065 0.2794)
			(end 0.12065 0.3048)
			(stroke
				(width 0.1)
				(type default)
			)
			(layer "B.Fab")
		)
		(fp_line
			(start -0.12065 -0.2794)
			(end -0.12065 -0.3048)
			(stroke
				(width 0.1)
				(type default)
			)
			(layer "B.Fab")
		)
		(fp_line
			(start 0.12065 -0.2794)
			(end -0.12065 -0.2794)
			(stroke
				(width 0.1)
				(type default)
			)
			(layer "B.Fab")
		)
		(fp_line
			(start -0.67945 -0.3048)
			(end -0.67945 0.3048)
			(stroke
				(width 0.1)
				(type default)
			)
			(layer "B.Fab")
		)
		(fp_line
			(start -0.12065 -0.3048)
			(end -0.67945 -0.3048)
			(stroke
				(width 0.1)
				(type default)
			)
			(layer "B.Fab")
		)
		(fp_line
			(start 0.12065 -0.305054)
			(end 0.12065 -0.2794)
			(stroke
				(width 0.1)
				(type default)
			)
			(layer "B.Fab")
		)
		(fp_line
			(start 0.67945 -0.305054)
			(end 0.12065 -0.305054)
			(stroke
				(width 0.1)
				(type default)
			)
			(layer "B.Fab")
		)
		(pad "1" smd circle
			(at 0.40005 0 90)
			(size 0 0)
			(layers "B.Cu" "B.Mask" "B.Paste")
			(net "HGX_DETECT_N")
		)
		(pad "2" smd circle
			(at -0.40005 0 90)
			(size 0 0)
			(layers "B.Cu" "B.Mask" "B.Paste")
			(net "GND")
		)
	)
)
